(kicad_pcb
	(version 20260206)
	(generator "pcbnew")
	(generator_version "10.0")
	(general
		(thickness 1.6)
		(legacy_teardrops no)
	)
	(paper "A4")
	(title_block
		(title "peb — Lightning_PEB_BRD.brd")
		(comment 1 "Lightning (Wiwynn / Facebook NVMe JBOF) / footprints 1291-1298 of 2563")
	)
	(layers
		(0 "F.Cu" signal "TOP")
		(4 "In1.Cu" signal "L2GND")
		(6 "In2.Cu" signal "L3")
		(8 "In3.Cu" signal "L4VCC")
		(10 "In4.Cu" signal "L5VCC")
		(12 "In5.Cu" signal "L6")
		(14 "In6.Cu" signal "L7GND")
		(2 "B.Cu" signal "BOTTOM")
		(9 "F.Adhes" user "F.Adhesive")
		(11 "B.Adhes" user "B.Adhesive")
		(13 "F.Paste" user "Package Geometry/Pastemask Top")
		(15 "B.Paste" user "Package Geometry/Pastemask Bottom")
		(5 "F.SilkS" user "Ref Des/Silkscreen Top")
		(7 "B.SilkS" user "Ref Des/Silkscreen Bottom")
		(1 "F.Mask" user "Board Geometry/Soldermask Top")
		(3 "B.Mask" user "Board Geometry/Soldermask Bottom")
		(17 "Dwgs.User" user "User.Drawings")
		(19 "Cmts.User" user "User.Comments")
		(21 "Eco1.User" user "User.Eco1")
		(23 "Eco2.User" user "User.Eco2")
		(25 "Edge.Cuts" user "Board Geometry/Outline")
		(27 "Margin" user)
		(31 "F.CrtYd" user "Package Geometry/Place Bound Top")
		(29 "B.CrtYd" user "Package Geometry/Place Bound Bottom")
		(35 "F.Fab" user "Ref Des/Assembly Top")
		(33 "B.Fab" user "Ref Des/Assembly Bottom")
	)
	(footprint ""
		(layer "F.Cu")
		(at 50.251614 -109.764068)
		(property "Reference" "R330"
			(at 0 0 0)
			(layer "F.SilkS")
			(hide yes)
			(effects
				(font
					(size 1.27 1.27)
				)
			)
		)
		(property "Value" "4K7R2F-GP"
			(at 0.064008 -3.993896 0)
			(unlocked yes)
			(layer "F.Fab")
			(hide yes)
			(effects
				(font
					(size 1.016 1.016)
					(thickness 0.1524)
				)
			)
		)
		(property "Device Type" "R402H16"
			(at 0.064008 -5.517896 0)
			(unlocked yes)
			(layer "F.Fab")
			(hide yes)
			(effects
				(font
					(size 1.016 1.016)
					(thickness 0.1524)
				)
			)
		)
		(duplicate_pad_numbers_are_jumpers no)
		(fp_line
			(start -0.508 -0.9398)
			(end -0.508 0.9398)
			(stroke
				(width 0.1524)
				(type default)
			)
			(layer "F.SilkS")
		)
		(fp_line
			(start 0.508 -0.9398)
			(end -0.508 -0.9398)
			(stroke
				(width 0.1524)
				(type default)
			)
			(layer "F.SilkS")
		)
		(fp_rect
			(start -0.508 0.9398)
			(end 0.508 -0.9398)
			(stroke
				(width 0)
				(type default)
			)
			(fill no)
			(layer "F.CrtYd")
		)
		(fp_rect
			(start -0.508 0.9398)
			(end 0.508 -0.9398)
			(stroke
				(width 0)
				(type default)
			)
			(fill no)
			(layer "F.Fab")
		)
		(pad "1" smd custom
			(at 0 -0.4445)
			(size 0.1397 0.1397)
			(layers "F.Cu" "F.Mask" "F.Paste")
			(net "P3V3_STBY")
			(options
				(clearance outline)
				(anchor circle)
			)
			(primitives
				(gr_poly
					(pts
						(arc
							(start -0.1778 -0.2794)
							(mid -0.249642 -0.249642)
							(end -0.2794 -0.1778)
						)
						(arc
							(start -0.2794 0.1778)
							(mid -0.249642 0.249642)
							(end -0.1778 0.2794)
						)
						(arc
							(start 0.1778 0.2794)
							(mid 0.249642 0.249642)
							(end 0.2794 0.1778)
						)
						(arc
							(start 0.2794 -0.1778)
							(mid 0.249642 -0.249642)
							(end 0.1778 -0.2794)
						)
					)
					(width 0)
					(fill yes)
				)
			)
		)
		(pad "2" smd custom
			(at 0 0.4445)
			(size 0.1397 0.1397)
			(layers "F.Cu" "F.Mask" "F.Paste")
			(net "I2C7_LS_G1")
			(options
				(clearance outline)
				(anchor circle)
			)
			(primitives
				(gr_poly
					(pts
						(arc
							(start -0.1778 -0.2794)
							(mid -0.249642 -0.249642)
							(end -0.2794 -0.1778)
						)
						(arc
							(start -0.2794 0.1778)
							(mid -0.249642 0.249642)
							(end -0.1778 0.2794)
						)
						(arc
							(start 0.1778 0.2794)
							(mid 0.249642 0.249642)
							(end 0.2794 0.1778)
						)
						(arc
							(start 0.2794 -0.1778)
							(mid 0.249642 -0.249642)
							(end 0.1778 -0.2794)
						)
					)
					(width 0)
					(fill yes)
				)
			)
		)
	)
	(footprint ""
		(layer "F.Cu")
		(at 116.604034 -30.617414 180)
		(property "Reference" "C132"
			(at 0 0 180)
			(layer "F.SilkS")
			(hide yes)
			(effects
				(font
					(size 1.27 1.27)
				)
			)
		)
		(property "Value" "SCD047U25V2KX-GP"
			(at 1.1811 -2.7051 180)
			(unlocked yes)
			(layer "F.Fab")
			(hide yes)
			(effects
				(font
					(size 1.016 1.016)
					(thickness 0.1524)
				)
			)
		)
		(property "Device Type" "C402H22"
			(at 1.1811 -4.2291 180)
			(unlocked yes)
			(layer "F.Fab")
			(hide yes)
			(effects
				(font
					(size 1.016 1.016)
					(thickness 0.1524)
				)
			)
		)
		(duplicate_pad_numbers_are_jumpers no)
		(fp_rect
			(start -0.4318 0.9525)
			(end 0.4318 -0.9525)
			(stroke
				(width 0)
				(type default)
			)
			(fill no)
			(layer "F.CrtYd")
		)
		(fp_rect
			(start -0.4318 0.9525)
			(end 0.4318 -0.9525)
			(stroke
				(width 0)
				(type default)
			)
			(fill no)
			(layer "F.Fab")
		)
		(pad "1" smd custom
			(at 0 -0.4445 180)
			(size 0.1524 0.1524)
			(layers "F.Cu" "F.Mask" "F.Paste")
			(net "P3V3_STBY")
			(options
				(clearance outline)
				(anchor circle)
			)
			(primitives
				(gr_poly
					(pts
						(arc
							(start 0.3048 -0.2032)
							(mid 0.275042 -0.275042)
							(end 0.2032 -0.3048)
						)
						(arc
							(start -0.2032 -0.3048)
							(mid -0.275042 -0.275042)
							(end -0.3048 -0.2032)
						)
						(arc
							(start -0.3048 0.2032)
							(mid -0.275042 0.275042)
							(end -0.2032 0.3048)
						)
						(arc
							(start 0.2032 0.3048)
							(mid 0.275042 0.275042)
							(end 0.3048 0.2032)
						)
					)
					(width 0)
					(fill yes)
				)
			)
		)
		(pad "2" smd custom
			(at 0 0.4445 180)
			(size 0.1524 0.1524)
			(layers "F.Cu" "F.Mask" "F.Paste")
			(net "GND")
			(options
				(clearance outline)
				(anchor circle)
			)
			(primitives
				(gr_poly
					(pts
						(arc
							(start 0.3048 -0.2032)
							(mid 0.275042 -0.275042)
							(end 0.2032 -0.3048)
						)
						(arc
							(start -0.2032 -0.3048)
							(mid -0.275042 -0.275042)
							(end -0.3048 -0.2032)
						)
						(arc
							(start -0.3048 0.2032)
							(mid -0.275042 0.275042)
							(end -0.2032 0.3048)
						)
						(arc
							(start 0.2032 0.3048)
							(mid 0.275042 0.275042)
							(end 0.3048 0.2032)
						)
					)
					(width 0)
					(fill yes)
				)
			)
		)
	)
	(footprint ""
		(layer "F.Cu")
		(at 221.845124 -190.582296)
		(property "Reference" "R7965"
			(at 0 0 0)
			(layer "F.SilkS")
			(hide yes)
			(effects
				(font
					(size 1.27 1.27)
				)
			)
		)
		(property "Value" "0R2J-2-GP"
			(at 0.064008 -3.993896 0)
			(unlocked yes)
			(layer "F.Fab")
			(hide yes)
			(effects
				(font
					(size 1.016 1.016)
					(thickness 0.1524)
				)
			)
		)
		(property "Device Type" "R402H16"
			(at 0.064008 -5.517896 0)
			(unlocked yes)
			(layer "F.Fab")
			(hide yes)
			(effects
				(font
					(size 1.016 1.016)
					(thickness 0.1524)
				)
			)
		)
		(duplicate_pad_numbers_are_jumpers no)
		(fp_line
			(start -0.508 -0.9398)
			(end -0.508 0.9398)
			(stroke
				(width 0.1524)
				(type default)
			)
			(layer "F.SilkS")
		)
		(fp_line
			(start 0.508 -0.9398)
			(end -0.508 -0.9398)
			(stroke
				(width 0.1524)
				(type default)
			)
			(layer "F.SilkS")
		)
		(fp_rect
			(start -0.508 0.9398)
			(end 0.508 -0.9398)
			(stroke
				(width 0)
				(type default)
			)
			(fill no)
			(layer "F.CrtYd")
		)
		(fp_rect
			(start -0.508 0.9398)
			(end 0.508 -0.9398)
			(stroke
				(width 0)
				(type default)
			)
			(fill no)
			(layer "F.Fab")
		)
		(pad "1" smd custom
			(at 0 -0.4445)
			(size 0.1397 0.1397)
			(layers "F.Cu" "F.Mask" "F.Paste")
			(net "SSD_PWREN3")
			(options
				(clearance outline)
				(anchor circle)
			)
			(primitives
				(gr_poly
					(pts
						(arc
							(start -0.1778 -0.2794)
							(mid -0.249642 -0.249642)
							(end -0.2794 -0.1778)
						)
						(arc
							(start -0.2794 0.1778)
							(mid -0.249642 0.249642)
							(end -0.1778 0.2794)
						)
						(arc
							(start 0.1778 0.2794)
							(mid 0.249642 0.249642)
							(end 0.2794 0.1778)
						)
						(arc
							(start 0.2794 -0.1778)
							(mid 0.249642 -0.249642)
							(end 0.1778 -0.2794)
						)
					)
					(width 0)
					(fill yes)
				)
			)
		)
		(pad "2" smd custom
			(at 0 0.4445)
			(size 0.1397 0.1397)
			(layers "F.Cu" "F.Mask" "F.Paste")
			(net "SSD_PWREN3_R")
			(options
				(clearance outline)
				(anchor circle)
			)
			(primitives
				(gr_poly
					(pts
						(arc
							(start -0.1778 -0.2794)
							(mid -0.249642 -0.249642)
							(end -0.2794 -0.1778)
						)
						(arc
							(start -0.2794 0.1778)
							(mid -0.249642 0.249642)
							(end -0.1778 0.2794)
						)
						(arc
							(start 0.1778 0.2794)
							(mid 0.249642 0.249642)
							(end 0.2794 0.1778)
						)
						(arc
							(start 0.2794 -0.1778)
							(mid 0.249642 -0.249642)
							(end 0.1778 -0.2794)
						)
					)
					(width 0)
					(fill yes)
				)
			)
		)
	)
	(footprint ""
		(layer "F.Cu")
		(at 181.61 -24.511 -90)
		(property "Reference" "C409"
			(at 0 0 270)
			(layer "F.SilkS")
			(hide yes)
			(effects
				(font
					(size 1.27 1.27)
				)
			)
		)
		(property "Value" "SCD22U10V2KX-1GP"
			(at 1.1811 -2.7051 270)
			(unlocked yes)
			(layer "F.Fab")
			(hide yes)
			(effects
				(font
					(size 1.016 1.016)
					(thickness 0.1524)
				)
			)
		)
		(property "Device Type" "C402H22"
			(at 1.1811 -4.2291 270)
			(unlocked yes)
			(layer "F.Fab")
			(hide yes)
			(effects
				(font
					(size 1.016 1.016)
					(thickness 0.1524)
				)
			)
		)
		(duplicate_pad_numbers_are_jumpers no)
		(fp_rect
			(start -0.4318 0.9525)
			(end 0.4318 -0.9525)
			(stroke
				(width 0)
				(type default)
			)
			(fill no)
			(layer "F.CrtYd")
		)
		(fp_rect
			(start -0.4318 0.9525)
			(end 0.4318 -0.9525)
			(stroke
				(width 0)
				(type default)
			)
			(fill no)
			(layer "F.Fab")
		)
		(pad "1" smd custom
			(at 0 -0.4445 270)
			(size 0.1524 0.1524)
			(layers "F.Cu" "F.Mask" "F.Paste")
			(net "PCIE_TX_CAP_P94")
			(options
				(clearance outline)
				(anchor circle)
			)
			(primitives
				(gr_poly
					(pts
						(arc
							(start 0.3048 -0.2032)
							(mid 0.275042 -0.275042)
							(end 0.2032 -0.3048)
						)
						(arc
							(start -0.2032 -0.3048)
							(mid -0.275042 -0.275042)
							(end -0.3048 -0.2032)
						)
						(arc
							(start -0.3048 0.2032)
							(mid -0.275042 0.275042)
							(end -0.2032 0.3048)
						)
						(arc
							(start 0.2032 0.3048)
							(mid 0.275042 0.275042)
							(end 0.3048 0.2032)
						)
					)
					(width 0)
					(fill yes)
				)
			)
		)
		(pad "2" smd custom
			(at 0 0.4445 270)
			(size 0.1524 0.1524)
			(layers "F.Cu" "F.Mask" "F.Paste")
			(net "PCIE_TX_P94")
			(options
				(clearance outline)
				(anchor circle)
			)
			(primitives
				(gr_poly
					(pts
						(arc
							(start 0.3048 -0.2032)
							(mid 0.275042 -0.275042)
							(end 0.2032 -0.3048)
						)
						(arc
							(start -0.2032 -0.3048)
							(mid -0.275042 -0.275042)
							(end -0.3048 -0.2032)
						)
						(arc
							(start -0.3048 0.2032)
							(mid -0.275042 0.275042)
							(end -0.2032 0.3048)
						)
						(arc
							(start 0.2032 0.3048)
							(mid 0.275042 0.275042)
							(end 0.3048 0.2032)
						)
					)
					(width 0)
					(fill yes)
				)
			)
		)
	)
	(footprint ""
		(layer "F.Cu")
		(at 167.408098 -212.420454 180)
		(property "Reference" "C161"
			(at 0 0 180)
			(layer "F.SilkS")
			(hide yes)
			(effects
				(font
					(size 1.27 1.27)
				)
			)
		)
		(property "Value" "SCD22U10V2KX-1GP"
			(at 1.1811 -2.7051 180)
			(unlocked yes)
			(layer "F.Fab")
			(hide yes)
			(effects
				(font
					(size 1.016 1.016)
					(thickness 0.1524)
				)
			)
		)
		(property "Device Type" "C402H22"
			(at 1.1811 -4.2291 180)
			(unlocked yes)
			(layer "F.Fab")
			(hide yes)
			(effects
				(font
					(size 1.016 1.016)
					(thickness 0.1524)
				)
			)
		)
		(duplicate_pad_numbers_are_jumpers no)
		(fp_rect
			(start -0.4318 0.9525)
			(end 0.4318 -0.9525)
			(stroke
				(width 0)
				(type default)
			)
			(fill no)
			(layer "F.CrtYd")
		)
		(fp_rect
			(start -0.4318 0.9525)
			(end 0.4318 -0.9525)
			(stroke
				(width 0)
				(type default)
			)
			(fill no)
			(layer "F.Fab")
		)
		(pad "1" smd custom
			(at 0 -0.4445 180)
			(size 0.1524 0.1524)
			(layers "F.Cu" "F.Mask" "F.Paste")
			(net "PCIE_TX_CAP_N51")
			(options
				(clearance outline)
				(anchor circle)
			)
			(primitives
				(gr_poly
					(pts
						(arc
							(start 0.3048 -0.2032)
							(mid 0.275042 -0.275042)
							(end 0.2032 -0.3048)
						)
						(arc
							(start -0.2032 -0.3048)
							(mid -0.275042 -0.275042)
							(end -0.3048 -0.2032)
						)
						(arc
							(start -0.3048 0.2032)
							(mid -0.275042 0.275042)
							(end -0.2032 0.3048)
						)
						(arc
							(start 0.2032 0.3048)
							(mid 0.275042 0.275042)
							(end 0.3048 0.2032)
						)
					)
					(width 0)
					(fill yes)
				)
			)
		)
		(pad "2" smd custom
			(at 0 0.4445 180)
			(size 0.1524 0.1524)
			(layers "F.Cu" "F.Mask" "F.Paste")
			(net "PCIE_TX_N51")
			(options
				(clearance outline)
				(anchor circle)
			)
			(primitives
				(gr_poly
					(pts
						(arc
							(start 0.3048 -0.2032)
							(mid 0.275042 -0.275042)
							(end 0.2032 -0.3048)
						)
						(arc
							(start -0.2032 -0.3048)
							(mid -0.275042 -0.275042)
							(end -0.3048 -0.2032)
						)
						(arc
							(start -0.3048 0.2032)
							(mid -0.275042 0.275042)
							(end -0.2032 0.3048)
						)
						(arc
							(start 0.2032 0.3048)
							(mid 0.275042 0.275042)
							(end 0.3048 0.2032)
						)
					)
					(width 0)
					(fill yes)
				)
			)
		)
	)
	(footprint ""
		(layer "F.Cu")
		(at 64.389 -89.2556 -90)
		(property "Reference" "Q10"
			(at 0 0 270)
			(layer "F.SilkS")
			(hide yes)
			(effects
				(font
					(size 1.27 1.27)
				)
			)
		)
		(property "Value" "2N7002DW-7F-GP"
			(at -2.3622 -8.2042 270)
			(unlocked yes)
			(layer "F.Fab")
			(hide yes)
			(effects
				(font
					(size 1.016 1.016)
					(thickness 0.1524)
				)
			)
		)
		(property "Device Type" "SOT-363H44"
			(at -2.3622 -10.1092 270)
			(unlocked yes)
			(layer "F.Fab")
			(hide yes)
			(effects
				(font
					(size 1.016 1.016)
					(thickness 0.1524)
				)
			)
		)
		(duplicate_pad_numbers_are_jumpers no)
		(fp_line
			(start -1.4478 1.7018)
			(end 1.4478 1.7018)
			(stroke
				(width 0.1524)
				(type default)
			)
			(layer "F.SilkS")
		)
		(fp_line
			(start 1.4478 1.7018)
			(end 1.4478 -1.7018)
			(stroke
				(width 0.1524)
				(type default)
			)
			(layer "F.SilkS")
		)
		(fp_line
			(start -1.27 1.524)
			(end -1.27 0.6604)
			(stroke
				(width 0.4826)
				(type default)
			)
			(layer "F.SilkS")
		)
		(fp_line
			(start -1.4478 -1.7018)
			(end -1.4478 1.7018)
			(stroke
				(width 0.1524)
				(type default)
			)
			(layer "F.SilkS")
		)
		(fp_line
			(start 1.4478 -1.7018)
			(end -1.4478 -1.7018)
			(stroke
				(width 0.1524)
				(type default)
			)
			(layer "F.SilkS")
		)
		(fp_poly
			(pts
				(xy -1.524 -1.778) (xy 1.524 -1.778) (xy 1.524 1.778) (xy -1.524 1.778)
			)
			(stroke
				(width 0)
				(type default)
			)
			(fill no)
			(layer "F.CrtYd")
		)
		(fp_poly
			(pts
				(xy -1.524 -1.778) (xy 1.524 -1.778) (xy 1.524 1.778) (xy -1.524 1.778)
			)
			(stroke
				(width 0)
				(type default)
			)
			(fill no)
			(layer "F.Fab")
		)
		(pad "1" smd rect
			(at -0.65024 0.9398 270)
			(size 0.4064 1.016)
			(layers "F.Cu" "F.Mask" "F.Paste")
			(net "GND")
		)
		(pad "2" smd rect
			(at 0 0.9398 270)
			(size 0.4064 1.016)
			(layers "F.Cu" "F.Mask" "F.Paste")
			(net "INVERTER_G2")
		)
		(pad "3" smd rect
			(at 0.65024 0.9398 270)
			(size 0.4064 1.016)
			(layers "F.Cu" "F.Mask" "F.Paste")
			(net "INVERTER_G2")
		)
		(pad "4" smd rect
			(at 0.65024 -0.9398 270)
			(size 0.4064 1.016)
			(layers "F.Cu" "F.Mask" "F.Paste")
			(net "GND")
		)
		(pad "5" smd rect
			(at 0 -0.9398 270)
			(size 0.4064 1.016)
			(layers "F.Cu" "F.Mask" "F.Paste")
			(net "INVERTER_G1")
		)
		(pad "6" smd rect
			(at -0.65024 -0.9398 270)
			(size 0.4064 1.016)
			(layers "F.Cu" "F.Mask" "F.Paste")
			(net "HB_OUT")
		)
	)
	(footprint ""
		(layer "F.Cu")
		(at 39.2938 -117.1194)
		(property "Reference" "TP325"
			(at 0 0 0)
			(layer "F.SilkS")
			(hide yes)
			(effects
				(font
					(size 1.27 1.27)
				)
			)
		)
		(property "Value" "TPAD28-2-GP"
			(at -0.0127 -1.6637 0)
			(unlocked yes)
			(layer "F.Fab")
			(hide yes)
			(effects
				(font
					(size 1.016 1.016)
					(thickness 0.1524)
				)
			)
		)
		(property "Device Type" "TPAD28"
			(at -0.0127 -3.1877 0)
			(unlocked yes)
			(layer "F.Fab")
			(hide yes)
			(effects
				(font
					(size 1.016 1.016)
					(thickness 0.1524)
				)
			)
		)
		(duplicate_pad_numbers_are_jumpers no)
		(fp_poly
			(pts
				(arc
					(start 0.3556 0)
					(mid -0.3556 0)
					(end 0.3556 0)
				)
			)
			(stroke
				(width 0)
				(type default)
			)
			(fill no)
			(layer "F.CrtYd")
		)
		(fp_poly
			(pts
				(arc
					(start 0.6096 0)
					(mid -0.6096 0)
					(end 0.6096 0)
				)
			)
			(stroke
				(width 0)
				(type default)
			)
			(fill no)
			(layer "F.Fab")
		)
		(pad "1" smd circle
			(at 0 0)
			(size 0.7112 0.7112)
			(layers "F.Cu" "F.Mask" "F.Paste")
			(net "TP_GPIOU0")
		)
	)
	(footprint ""
		(layer "F.Cu")
		(at 7.5692 -81.5848 90)
		(property "Reference" "C233"
			(at 0 0 90)
			(layer "F.SilkS")
			(hide yes)
			(effects
				(font
					(size 1.27 1.27)
				)
			)
		)
		(property "Value" "SC1U10V2KX-4-GP"
			(at 1.1811 -2.7051 90)
			(unlocked yes)
			(layer "F.Fab")
			(hide yes)
			(effects
				(font
					(size 1.016 1.016)
					(thickness 0.1524)
				)
			)
		)
		(property "Device Type" "C402H22"
			(at 1.1811 -4.2291 90)
			(unlocked yes)
			(layer "F.Fab")
			(hide yes)
			(effects
				(font
					(size 1.016 1.016)
					(thickness 0.1524)
				)
			)
		)
		(duplicate_pad_numbers_are_jumpers no)
		(fp_rect
			(start -0.4318 0.9525)
			(end 0.4318 -0.9525)
			(stroke
				(width 0)
				(type default)
			)
			(fill no)
			(layer "F.CrtYd")
		)
		(fp_rect
			(start -0.4318 0.9525)
			(end 0.4318 -0.9525)
			(stroke
				(width 0)
				(type default)
			)
			(fill no)
			(layer "F.Fab")
		)
		(pad "1" smd custom
			(at 0 -0.4445 90)
			(size 0.1524 0.1524)
			(layers "F.Cu" "F.Mask" "F.Paste")
			(net "P3V3_STBY")
			(options
				(clearance outline)
				(anchor circle)
			)
			(primitives
				(gr_poly
					(pts
						(arc
							(start 0.3048 -0.2032)
							(mid 0.275042 -0.275042)
							(end 0.2032 -0.3048)
						)
						(arc
							(start -0.2032 -0.3048)
							(mid -0.275042 -0.275042)
							(end -0.3048 -0.2032)
						)
						(arc
							(start -0.3048 0.2032)
							(mid -0.275042 0.275042)
							(end -0.2032 0.3048)
						)
						(arc
							(start 0.2032 0.3048)
							(mid 0.275042 0.275042)
							(end 0.3048 0.2032)
						)
					)
					(width 0)
					(fill yes)
				)
			)
		)
		(pad "2" smd custom
			(at 0 0.4445 90)
			(size 0.1524 0.1524)
			(layers "F.Cu" "F.Mask" "F.Paste")
			(net "GND")
			(options
				(clearance outline)
				(anchor circle)
			)
			(primitives
				(gr_poly
					(pts
						(arc
							(start 0.3048 -0.2032)
							(mid 0.275042 -0.275042)
							(end 0.2032 -0.3048)
						)
						(arc
							(start -0.2032 -0.3048)
							(mid -0.275042 -0.275042)
							(end -0.3048 -0.2032)
						)
						(arc
							(start -0.3048 0.2032)
							(mid -0.275042 0.275042)
							(end -0.2032 0.3048)
						)
						(arc
							(start 0.2032 0.3048)
							(mid 0.275042 0.275042)
							(end 0.3048 0.2032)
						)
					)
					(width 0)
					(fill yes)
				)
			)
		)
	)
)
